# SCM (Grand Teton) — schematic netlist excerpt (pin names and nets, part order shuffled) for the footprints in the layout excerpt that follows; sources: Cadence DE-HDL packaged netlist, KiCad conversion of 12092022_DA0F0TMDCD0_F0T_Management_Board_D_brd_V3_OCP.brd

U1  K4A8G165WCBCTD  K4A8G165WC-BCTD IC  pkg BGA96XB  page 20
  VDDQ0  = P1V2_AUX
  VSSQ0  = GND
  DQU0  = M_BMC_DDR4_DQ<8>
  DQSU_C  = M_BMC_DDR4_DQS1_N
  VSSQ1  = GND
  VDDQ1  = P1V2_AUX
  VPP0  = P2V5_AUX
  VSS0  = GND
  VDD0  = P1V2_AUX
  DQSU_T  = M_BMC_DDR4_DQS1_P
  DQU1  = M_BMC_DDR4_DQ<9>
  VDD1  = P1V2_AUX
  VDDQ2  = P1V2_AUX
  DQU4  = M_BMC_DDR4_DQ<12>
  DQU2  = M_BMC_DDR4_DQ<10>
  DQU3  = M_BMC_DDR4_DQ<11>
  DQU5  = M_BMC_DDR4_DQ<13>
  VSSQ2  = GND
  VDD2  = P1V2_AUX
  VSSQ3  = GND
  DQU6  = M_BMC_DDR4_DQ<14>
  DQU7  = M_BMC_DDR4_DQ<15>
  VSSQ4  = GND
  VDDQ3  = P1V2_AUX
  VSS1  = GND
  \dmu_n||dbiu_n\  = M_BMC_DDR4_MDM1
  VSSQ5  = GND
  \dml_n||dbil_n\  = M_BMC_DDR4_MDM0
  VSSQ6  = GND
  VSS2  = M_BMC_DDR4_ZQU
  VSSQ7  = GND
  VDDQ4  = P1V2_AUX
  DQSL_C  = M_BMC_DDR4_DQS0_N
  DQL1  = M_BMC_DDR4_DQ<1>
  VDDQ5  = P1V2_AUX
  ZQ  = PD_M_BMC_DDR4_ZQ
  VDDQ6  = P1V2_AUX
  DQL0  = M_BMC_DDR4_DQ<0>
  DQSL_T  = M_BMC_DDR4_DQS0_P
  VDD3  = P1V2_AUX
  VSS3  = GND
  VDDQ7  = P1V2_AUX
  VSSQ8  = GND
  DQL4  = M_BMC_DDR4_DQ<4>
  DQL2  = M_BMC_DDR4_DQ<2>
  DQL3  = M_BMC_DDR4_DQ<3>
  DQL5  = M_BMC_DDR4_DQ<5>
  VSSQ9  = GND
  VDD4  = P1V2_AUX
  VDDQ8  = P1V2_AUX
  DQL6  = M_BMC_DDR4_DQ<6>
  DQL7  = M_BMC_DDR4_DQ<7>
  VDDQ9  = P1V2_AUX
  VDD5  = P1V2_AUX
  VSS4  = GND
  CKE  = M_BMC_DDR4_MCKE
  ODT  = M_BMC_DDR4_MODT
  CK_T  = M_BMC_DDR4_MCLK_DP
  CK_C  = M_BMC_DDR4_MCLK_DN
  VSS5  = GND
  VDD6  = P1V2_AUX
  \we_n||a14\  = M_BMC_DDR4_MWE_N
  ACT_N  = M_BMC_DDR4_MACT_N
  CS_N  = M_BMC_DDR4_MCS_N
  RAS_N  = M_BMC_DDR4_MRAS_N
  VDD7  = P1V2_AUX
  VREFCA  = P0V6_DDR_VREF_AUX
  BG0  = M_BMC_DDR4_MBG0
  \a10||ap\  = M_BMC_DDR4_MA<10>
  \a12||bc_n\  = M_BMC_DDR4_MA<12>
  \cas_n||a15\  = M_BMC_DDR4_MCAS_N
  VSS6  = M_BMC_DDR4_BG1
  VSS7  = GND
  BA0  = M_BMC_DDR4_MBA0
  A4  = M_BMC_DDR4_MA<4>
  A3  = M_BMC_DDR4_MA<3>
  BA1  = M_BMC_DDR4_MBA1
  TEN  = PD_M_BMC_DDR4_TEN
  RESET_N  = M_BMC_DDR4_RST_N
  A6  = M_BMC_DDR4_MA<6>
  A0  = M_BMC_DDR4_MA<0>
  A1  = M_BMC_DDR4_MA<1>
  A5  = M_BMC_DDR4_MA<5>
  ALERT_N  = M_BMC_DDR4_ALERT_N
  VDD8  = P1V2_AUX
  A8  = M_BMC_DDR4_MA<8>
  A2  = M_BMC_DDR4_MA<2>
  A9  = M_BMC_DDR4_MA<9>
  A7  = M_BMC_DDR4_MA<7>
  VPP1  = P2V5_AUX
  VSS8  = GND
  A11  = M_BMC_DDR4_MA<11>
  PAR  = PD_M_BMC_DDR4_PAR
  NC1  = GND
  A13  = M_BMC_DDR4_MA<13>
  VDD9  = P1V2_AUX

(kicad_pcb
	(version 20260206)
	(generator "pcbnew")
	(generator_version "10.0")
	(general
		(thickness 1.6)
		(legacy_teardrops no)
	)
	(paper "A4")
	(title_block
		(title "12092022_DA0F0TMDCD0_F0T_Management_Board_D_brd_V3_OCP.brd")
		(comment 1 "Grand Teton / footprint 201 of 1440 (U1), pads 49-95 of 96")
	)
	(layers
		(0 "F.Cu" signal "TOP")
		(4 "In1.Cu" signal "GND")
		(6 "In2.Cu" signal "IN1")
		(8 "In3.Cu" signal "GND1")
		(10 "In4.Cu" signal "IN2")
		(12 "In5.Cu" signal "VCC")
		(14 "In6.Cu" signal "VCC1")
		(16 "In7.Cu" signal "IN3")
		(18 "In8.Cu" signal "GND2")
		(20 "In9.Cu" signal "IN4")
		(22 "In10.Cu" signal "GND3")
		(2 "B.Cu" signal "BOTTOM")
		(9 "F.Adhes" user "F.Adhesive")
		(11 "B.Adhes" user "B.Adhesive")
		(13 "F.Paste" user "Package Geometry/Pastemask Top")
		(15 "B.Paste" user "Package Geometry/Pastemask Bottom")
		(5 "F.SilkS" user "Ref Des/Silkscreen Top")
		(7 "B.SilkS" user "Ref Des/Silkscreen Bottom")
		(1 "F.Mask" user "Board Geometry/Soldermask Top")
		(3 "B.Mask" user "Board Geometry/Soldermask Bottom")
		(17 "Dwgs.User" user "User.Drawings")
		(19 "Cmts.User" user "User.Comments")
		(21 "Eco1.User" user "User.Eco1")
		(23 "Eco2.User" user "User.Eco2")
		(25 "Edge.Cuts" user "Board Geometry/Outline")
		(27 "Margin" user)
		(31 "F.CrtYd" user "Package Geometry/Place Bound Top")
		(29 "B.CrtYd" user "Package Geometry/Place Bound Bottom")
		(35 "F.Fab" user "Ref Des/Assembly Top")
		(33 "B.Fab" user "Ref Des/Assembly Bottom")
	)
	(footprint ""
		(layer "F.Cu")
		(at 76.252324 -47.907448)
		(property "Reference" "U1"
			(at -4.664456 -10.397744 0)
			(unlocked yes)
			(layer "F.SilkS")
			(effects
				(font
					(size 0.7874 0.5842)
					(thickness 0.1524)
				)
				(justify left)
			)
		)
		(property "Value" ""
			(at 0 0 0)
			(layer "F.Fab")
			(effects
				(font
					(size 1.27 1.27)
				)
			)
		)
		(duplicate_pad_numbers_are_jumpers no)
		(pad "J1" smd circle
			(at -3.199892 0.40005)
			(size 0.3683 0.3683)
			(layers "F.Cu" "F.Mask" "F.Paste")
			(net "P1V2_AUX")
		)
		(pad "J2" smd circle
			(at -2.400046 0.40005)
			(size 0.3683 0.3683)
			(layers "F.Cu" "F.Mask" "F.Paste")
			(net "P1V2_AUX")
		)
		(pad "J3" smd circle
			(at -1.599946 0.40005)
			(size 0.3683 0.3683)
			(layers "F.Cu" "F.Mask" "F.Paste")
			(net "M_BMC_DDR4_DQ<6>")
		)
		(pad "J7" smd circle
			(at 1.599946 0.40005)
			(size 0.3683 0.3683)
			(layers "F.Cu" "F.Mask" "F.Paste")
			(net "M_BMC_DDR4_DQ<7>")
		)
		(pad "J8" smd circle
			(at 2.400046 0.40005)
			(size 0.3683 0.3683)
			(layers "F.Cu" "F.Mask" "F.Paste")
			(net "P1V2_AUX")
		)
		(pad "J9" smd circle
			(at 3.199892 0.40005)
			(size 0.3683 0.3683)
			(layers "F.Cu" "F.Mask" "F.Paste")
			(net "P1V2_AUX")
		)
		(pad "K1" smd circle
			(at -3.199892 1.199896)
			(size 0.3683 0.3683)
			(layers "F.Cu" "F.Mask" "F.Paste")
			(net "GND")
		)
		(pad "K2" smd circle
			(at -2.400046 1.199896)
			(size 0.3683 0.3683)
			(layers "F.Cu" "F.Mask" "F.Paste")
			(net "M_BMC_DDR4_MCKE")
		)
		(pad "K3" smd circle
			(at -1.599946 1.199896)
			(size 0.3683 0.3683)
			(layers "F.Cu" "F.Mask" "F.Paste")
			(net "M_BMC_DDR4_MODT")
		)
		(pad "K7" smd circle
			(at 1.599946 1.199896)
			(size 0.3683 0.3683)
			(layers "F.Cu" "F.Mask" "F.Paste")
			(net "M_BMC_DDR4_MCLK_DP")
		)
		(pad "K8" smd circle
			(at 2.400046 1.199896)
			(size 0.3683 0.3683)
			(layers "F.Cu" "F.Mask" "F.Paste")
			(net "M_BMC_DDR4_MCLK_DN")
		)
		(pad "K9" smd circle
			(at 3.199892 1.199896)
			(size 0.3683 0.3683)
			(layers "F.Cu" "F.Mask" "F.Paste")
			(net "GND")
		)
		(pad "L1" smd circle
			(at -3.199892 1.999996)
			(size 0.3683 0.3683)
			(layers "F.Cu" "F.Mask" "F.Paste")
			(net "P1V2_AUX")
		)
		(pad "L2" smd circle
			(at -2.400046 1.999996)
			(size 0.3683 0.3683)
			(layers "F.Cu" "F.Mask" "F.Paste")
			(net "M_BMC_DDR4_MWE_N")
		)
		(pad "L3" smd circle
			(at -1.599946 1.999996)
			(size 0.3683 0.3683)
			(layers "F.Cu" "F.Mask" "F.Paste")
			(net "M_BMC_DDR4_MACT_N")
		)
		(pad "L7" smd circle
			(at 1.599946 1.999996)
			(size 0.3683 0.3683)
			(layers "F.Cu" "F.Mask" "F.Paste")
			(net "M_BMC_DDR4_MCS_N")
		)
		(pad "L8" smd circle
			(at 2.400046 1.999996)
			(size 0.3683 0.3683)
			(layers "F.Cu" "F.Mask" "F.Paste")
			(net "M_BMC_DDR4_MRAS_N")
		)
		(pad "L9" smd circle
			(at 3.199892 1.999996)
			(size 0.3683 0.3683)
			(layers "F.Cu" "F.Mask" "F.Paste")
			(net "P1V2_AUX")
		)
		(pad "M1" smd circle
			(at -3.199892 2.800096)
			(size 0.3683 0.3683)
			(layers "F.Cu" "F.Mask" "F.Paste")
			(net "P0V6_DDR_VREF_AUX")
		)
		(pad "M2" smd circle
			(at -2.400046 2.800096)
			(size 0.3683 0.3683)
			(layers "F.Cu" "F.Mask" "F.Paste")
			(net "M_BMC_DDR4_MBG0")
		)
		(pad "M3" smd circle
			(at -1.599946 2.800096)
			(size 0.3683 0.3683)
			(layers "F.Cu" "F.Mask" "F.Paste")
			(net "M_BMC_DDR4_MA<10>")
		)
		(pad "M7" smd circle
			(at 1.599946 2.800096)
			(size 0.3683 0.3683)
			(layers "F.Cu" "F.Mask" "F.Paste")
			(net "M_BMC_DDR4_MA<12>")
		)
		(pad "M8" smd circle
			(at 2.400046 2.800096)
			(size 0.3683 0.3683)
			(layers "F.Cu" "F.Mask" "F.Paste")
			(net "M_BMC_DDR4_MCAS_N")
		)
		(pad "M9" smd circle
			(at 3.199892 2.800096)
			(size 0.3683 0.3683)
			(layers "F.Cu" "F.Mask" "F.Paste")
			(net "M_BMC_DDR4_BG1")
		)
		(pad "N1" smd circle
			(at -3.199892 3.599942)
			(size 0.3683 0.3683)
			(layers "F.Cu" "F.Mask" "F.Paste")
			(net "GND")
		)
		(pad "N2" smd circle
			(at -2.400046 3.599942)
			(size 0.3683 0.3683)
			(layers "F.Cu" "F.Mask" "F.Paste")
			(net "M_BMC_DDR4_MBA0")
		)
		(pad "N3" smd circle
			(at -1.599946 3.599942)
			(size 0.3683 0.3683)
			(layers "F.Cu" "F.Mask" "F.Paste")
			(net "M_BMC_DDR4_MA<4>")
		)
		(pad "N7" smd circle
			(at 1.599946 3.599942)
			(size 0.3683 0.3683)
			(layers "F.Cu" "F.Mask" "F.Paste")
			(net "M_BMC_DDR4_MA<3>")
		)
		(pad "N8" smd circle
			(at 2.400046 3.599942)
			(size 0.3683 0.3683)
			(layers "F.Cu" "F.Mask" "F.Paste")
			(net "M_BMC_DDR4_MBA1")
		)
		(pad "N9" smd circle
			(at 3.199892 3.599942)
			(size 0.3683 0.3683)
			(layers "F.Cu" "F.Mask" "F.Paste")
			(net "PD_M_BMC_DDR4_TEN")
		)
		(pad "P1" smd circle
			(at -3.199892 4.400042)
			(size 0.3683 0.3683)
			(layers "F.Cu" "F.Mask" "F.Paste")
			(net "M_BMC_DDR4_RST_N")
		)
		(pad "P2" smd circle
			(at -2.400046 4.400042)
			(size 0.3683 0.3683)
			(layers "F.Cu" "F.Mask" "F.Paste")
			(net "M_BMC_DDR4_MA<6>")
		)
		(pad "P3" smd circle
			(at -1.599946 4.400042)
			(size 0.3683 0.3683)
			(layers "F.Cu" "F.Mask" "F.Paste")
			(net "M_BMC_DDR4_MA<0>")
		)
		(pad "P7" smd circle
			(at 1.599946 4.400042)
			(size 0.3683 0.3683)
			(layers "F.Cu" "F.Mask" "F.Paste")
			(net "M_BMC_DDR4_MA<1>")
		)
		(pad "P8" smd circle
			(at 2.400046 4.400042)
			(size 0.3683 0.3683)
			(layers "F.Cu" "F.Mask" "F.Paste")
			(net "M_BMC_DDR4_MA<5>")
		)
		(pad "P9" smd circle
			(at 3.199892 4.400042)
			(size 0.3683 0.3683)
			(layers "F.Cu" "F.Mask" "F.Paste")
			(net "M_BMC_DDR4_ALERT_N")
		)
		(pad "R1" smd circle
			(at -3.199892 5.199888)
			(size 0.3683 0.3683)
			(layers "F.Cu" "F.Mask" "F.Paste")
			(net "P1V2_AUX")
		)
		(pad "R2" smd circle
			(at -2.400046 5.199888)
			(size 0.3683 0.3683)
			(layers "F.Cu" "F.Mask" "F.Paste")
			(net "M_BMC_DDR4_MA<8>")
		)
		(pad "R3" smd circle
			(at -1.599946 5.199888)
			(size 0.3683 0.3683)
			(layers "F.Cu" "F.Mask" "F.Paste")
			(net "M_BMC_DDR4_MA<2>")
		)
		(pad "R7" smd circle
			(at 1.599946 5.199888)
			(size 0.3683 0.3683)
			(layers "F.Cu" "F.Mask" "F.Paste")
			(net "M_BMC_DDR4_MA<9>")
		)
		(pad "R8" smd circle
			(at 2.400046 5.199888)
			(size 0.3683 0.3683)
			(layers "F.Cu" "F.Mask" "F.Paste")
			(net "M_BMC_DDR4_MA<7>")
		)
		(pad "R9" smd circle
			(at 3.199892 5.199888)
			(size 0.3683 0.3683)
			(layers "F.Cu" "F.Mask" "F.Paste")
			(net "P2V5_AUX")
		)
		(pad "T1" smd circle
			(at -3.199892 5.999988)
			(size 0.3683 0.3683)
			(layers "F.Cu" "F.Mask" "F.Paste")
			(net "GND")
		)
		(pad "T2" smd circle
			(at -2.400046 5.999988)
			(size 0.3683 0.3683)
			(layers "F.Cu" "F.Mask" "F.Paste")
			(net "M_BMC_DDR4_MA<11>")
		)
		(pad "T3" smd circle
			(at -1.599946 5.999988)
			(size 0.3683 0.3683)
			(layers "F.Cu" "F.Mask" "F.Paste")
			(net "PD_M_BMC_DDR4_PAR")
		)
		(pad "T7" smd circle
			(at 1.599946 5.999988)
			(size 0.3683 0.3683)
			(layers "F.Cu" "F.Mask" "F.Paste")
			(net "GND")
		)
		(pad "T8" smd circle
			(at 2.400046 5.999988)
			(size 0.3683 0.3683)
			(layers "F.Cu" "F.Mask" "F.Paste")
			(net "M_BMC_DDR4_MA<13>")
		)
	)
)
